(kicad_pcb
	(version 20260206)
	(generator "pcbnew")
	(generator_version "10.0")
	(general
		(thickness 1.6)
		(legacy_teardrops no)
	)
	(paper "A4")
	(title_block
		(title "baseboard — 13948-1b.1110WZS1818.brd")
		(comment 1 "Honey Badger (Wiwynn) / footprints 916-922 of 2523")
	)
	(layers
		(0 "F.Cu" signal "TOP")
		(4 "In1.Cu" signal "L2GND")
		(6 "In2.Cu" signal "L3")
		(8 "In3.Cu" signal "L4VCC")
		(10 "In4.Cu" signal "L5VCC")
		(12 "In5.Cu" signal "L6")
		(14 "In6.Cu" signal "L7GND")
		(2 "B.Cu" signal "BOTTOM")
		(9 "F.Adhes" user "F.Adhesive")
		(11 "B.Adhes" user "B.Adhesive")
		(13 "F.Paste" user "Package Geometry/Pastemask Top")
		(15 "B.Paste" user "Package Geometry/Pastemask Bottom")
		(5 "F.SilkS" user "Ref Des/Silkscreen Top")
		(7 "B.SilkS" user "Ref Des/Silkscreen Bottom")
		(1 "F.Mask" user "Board Geometry/Soldermask Top")
		(3 "B.Mask" user "Board Geometry/Soldermask Bottom")
		(17 "Dwgs.User" user "User.Drawings")
		(19 "Cmts.User" user "User.Comments")
		(21 "Eco1.User" user "User.Eco1")
		(23 "Eco2.User" user "User.Eco2")
		(25 "Edge.Cuts" user "Board Geometry/Outline")
		(27 "Margin" user)
		(31 "F.CrtYd" user "Package Geometry/Place Bound Top")
		(29 "B.CrtYd" user "Package Geometry/Place Bound Bottom")
		(35 "F.Fab" user "Ref Des/Assembly Top")
		(33 "B.Fab" user "Ref Des/Assembly Bottom")
	)
	(footprint ""
		(layer "F.Cu")
		(at 218.059 -180.594 -90)
		(property "Reference" "R501"
			(at 0 0 270)
			(layer "F.SilkS")
			(hide yes)
			(effects
				(font
					(size 1.27 1.27)
				)
			)
		)
		(property "Value" "1KR2F-3-GP"
			(at 0.064008 -3.993896 270)
			(unlocked yes)
			(layer "F.Fab")
			(hide yes)
			(effects
				(font
					(size 1.016 1.016)
					(thickness 0.1524)
				)
			)
		)
		(property "Device Type" "R402H16"
			(at 0.064008 -5.517896 270)
			(unlocked yes)
			(layer "F.Fab")
			(hide yes)
			(effects
				(font
					(size 1.016 1.016)
					(thickness 0.1524)
				)
			)
		)
		(duplicate_pad_numbers_are_jumpers no)
		(fp_line
			(start -0.508 -0.9398)
			(end -0.508 0.9398)
			(stroke
				(width 0.1524)
				(type default)
			)
			(layer "F.SilkS")
		)
		(fp_line
			(start 0.508 -0.9398)
			(end -0.508 -0.9398)
			(stroke
				(width 0.1524)
				(type default)
			)
			(layer "F.SilkS")
		)
		(fp_rect
			(start -0.508 0.9398)
			(end 0.508 -0.9398)
			(stroke
				(width 0)
				(type default)
			)
			(fill no)
			(layer "F.CrtYd")
		)
		(fp_rect
			(start -0.508 0.9398)
			(end 0.508 -0.9398)
			(stroke
				(width 0)
				(type default)
			)
			(fill no)
			(layer "F.Fab")
		)
		(pad "1" smd custom
			(at 0 -0.4445 270)
			(size 0.1397 0.1397)
			(layers "F.Cu" "F.Mask" "F.Paste")
			(net "DIVIDER 2_IN_EXP")
			(options
				(clearance outline)
				(anchor circle)
			)
			(primitives
				(gr_poly
					(pts
						(arc
							(start -0.1778 -0.2794)
							(mid -0.249642 -0.249642)
							(end -0.2794 -0.1778)
						)
						(arc
							(start -0.2794 0.1778)
							(mid -0.249642 0.249642)
							(end -0.1778 0.2794)
						)
						(arc
							(start 0.1778 0.2794)
							(mid 0.249642 0.249642)
							(end 0.2794 0.1778)
						)
						(arc
							(start 0.2794 -0.1778)
							(mid 0.249642 -0.249642)
							(end 0.1778 -0.2794)
						)
					)
					(width 0)
					(fill yes)
				)
			)
		)
		(pad "2" smd custom
			(at 0 0.4445 270)
			(size 0.1397 0.1397)
			(layers "F.Cu" "F.Mask" "F.Paste")
			(net "GND")
			(options
				(clearance outline)
				(anchor circle)
			)
			(primitives
				(gr_poly
					(pts
						(arc
							(start -0.1778 -0.2794)
							(mid -0.249642 -0.249642)
							(end -0.2794 -0.1778)
						)
						(arc
							(start -0.2794 0.1778)
							(mid -0.249642 0.249642)
							(end -0.1778 0.2794)
						)
						(arc
							(start 0.1778 0.2794)
							(mid 0.249642 0.249642)
							(end 0.2794 0.1778)
						)
						(arc
							(start 0.2794 -0.1778)
							(mid 0.249642 -0.249642)
							(end 0.1778 -0.2794)
						)
					)
					(width 0)
					(fill yes)
				)
			)
		)
	)
	(footprint ""
		(layer "F.Cu")
		(at 275.59 -107.315)
		(property "Reference" "Q78"
			(at 0 0 0)
			(layer "F.SilkS")
			(hide yes)
			(effects
				(font
					(size 1.27 1.27)
				)
			)
		)
		(property "Value" "FDN359BN-GP-U"
			(at -3.175 0.254 0)
			(unlocked yes)
			(layer "F.Fab")
			(hide yes)
			(effects
				(font
					(size 1.016 1.016)
					(thickness 0.1524)
				)
			)
		)
		(property "Device Type" "SOT23DGS2D6H45"
			(at -3.175 -1.27 0)
			(unlocked yes)
			(layer "F.Fab")
			(hide yes)
			(effects
				(font
					(size 1.016 1.016)
					(thickness 0.1524)
				)
			)
		)
		(duplicate_pad_numbers_are_jumpers no)
		(fp_line
			(start -1.7018 -1.905)
			(end 1.7018 -1.905)
			(stroke
				(width 0.1524)
				(type default)
			)
			(layer "F.SilkS")
		)
		(fp_line
			(start -1.7018 1.905)
			(end -1.7018 -1.905)
			(stroke
				(width 0.1524)
				(type default)
			)
			(layer "F.SilkS")
		)
		(fp_line
			(start 1.7018 -1.905)
			(end 1.7018 1.905)
			(stroke
				(width 0.1524)
				(type default)
			)
			(layer "F.SilkS")
		)
		(fp_line
			(start 1.7018 1.905)
			(end -1.7018 1.905)
			(stroke
				(width 0.1524)
				(type default)
			)
			(layer "F.SilkS")
		)
		(fp_rect
			(start -2.0066 1.9812)
			(end 2.0066 -1.9812)
			(stroke
				(width 0)
				(type default)
			)
			(fill no)
			(layer "F.CrtYd")
		)
		(fp_rect
			(start -2.0066 1.9812)
			(end 2.0066 -1.9812)
			(stroke
				(width 0)
				(type default)
			)
			(fill no)
			(layer "F.Fab")
		)
		(pad "D" smd custom
			(at 0 -1.0922)
			(size 0.1651 0.1651)
			(layers "F.Cu" "F.Mask" "F.Paste")
			(net "P1V8_STBY")
			(options
				(clearance outline)
				(anchor circle)
			)
			(primitives
				(gr_poly
					(pts
						(arc
							(start 0.3302 -0.381)
							(mid 0.270684 -0.524684)
							(end 0.127 -0.5842)
						)
						(arc
							(start -0.127 -0.5842)
							(mid -0.270684 -0.524684)
							(end -0.3302 -0.381)
						)
						(arc
							(start -0.3302 0.381)
							(mid -0.270684 0.524684)
							(end -0.127 0.5842)
						)
						(arc
							(start 0.127 0.5842)
							(mid 0.270684 0.524684)
							(end 0.3302 0.381)
						)
					)
					(width 0)
					(fill yes)
				)
			)
		)
		(pad "G" smd custom
			(at -0.94996 1.0922)
			(size 0.1651 0.1651)
			(layers "F.Cu" "F.Mask" "F.Paste")
			(net "P1V8_C_EN_LV")
			(options
				(clearance outline)
				(anchor circle)
			)
			(primitives
				(gr_poly
					(pts
						(arc
							(start 0.3302 -0.381)
							(mid 0.270684 -0.524684)
							(end 0.127 -0.5842)
						)
						(arc
							(start -0.127 -0.5842)
							(mid -0.270684 -0.524684)
							(end -0.3302 -0.381)
						)
						(arc
							(start -0.3302 0.381)
							(mid -0.270684 0.524684)
							(end -0.127 0.5842)
						)
						(arc
							(start 0.127 0.5842)
							(mid 0.270684 0.524684)
							(end 0.3302 0.381)
						)
					)
					(width 0)
					(fill yes)
				)
			)
		)
		(pad "S" smd custom
			(at 0.94996 1.0922)
			(size 0.1651 0.1651)
			(layers "F.Cu" "F.Mask" "F.Paste")
			(net "P1V8_C")
			(options
				(clearance outline)
				(anchor circle)
			)
			(primitives
				(gr_poly
					(pts
						(arc
							(start 0.3302 -0.381)
							(mid 0.270684 -0.524684)
							(end 0.127 -0.5842)
						)
						(arc
							(start -0.127 -0.5842)
							(mid -0.270684 -0.524684)
							(end -0.3302 -0.381)
						)
						(arc
							(start -0.3302 0.381)
							(mid -0.270684 0.524684)
							(end -0.127 0.5842)
						)
						(arc
							(start 0.127 0.5842)
							(mid 0.270684 0.524684)
							(end 0.3302 0.381)
						)
					)
					(width 0)
					(fill yes)
				)
			)
		)
	)
	(footprint ""
		(layer "F.Cu")
		(at 333.912718 -151.234648 -90)
		(property "Reference" "R7898"
			(at 0 0 270)
			(layer "F.SilkS")
			(hide yes)
			(effects
				(font
					(size 1.27 1.27)
				)
			)
		)
		(property "Value" "4K7R2F-GP"
			(at 0.064008 -3.993896 270)
			(unlocked yes)
			(layer "F.Fab")
			(hide yes)
			(effects
				(font
					(size 1.016 1.016)
					(thickness 0.1524)
				)
			)
		)
		(property "Device Type" "R402H16"
			(at 0.064008 -5.517896 270)
			(unlocked yes)
			(layer "F.Fab")
			(hide yes)
			(effects
				(font
					(size 1.016 1.016)
					(thickness 0.1524)
				)
			)
		)
		(duplicate_pad_numbers_are_jumpers no)
		(fp_line
			(start -0.508 -0.9398)
			(end -0.508 0.9398)
			(stroke
				(width 0.1524)
				(type default)
			)
			(layer "F.SilkS")
		)
		(fp_line
			(start 0.508 -0.9398)
			(end -0.508 -0.9398)
			(stroke
				(width 0.1524)
				(type default)
			)
			(layer "F.SilkS")
		)
		(fp_rect
			(start -0.508 0.9398)
			(end 0.508 -0.9398)
			(stroke
				(width 0)
				(type default)
			)
			(fill no)
			(layer "F.CrtYd")
		)
		(fp_rect
			(start -0.508 0.9398)
			(end 0.508 -0.9398)
			(stroke
				(width 0)
				(type default)
			)
			(fill no)
			(layer "F.Fab")
		)
		(pad "1" smd custom
			(at 0 -0.4445 270)
			(size 0.1397 0.1397)
			(layers "F.Cu" "F.Mask" "F.Paste")
			(net "CFG_SEL0")
			(options
				(clearance outline)
				(anchor circle)
			)
			(primitives
				(gr_poly
					(pts
						(arc
							(start -0.1778 -0.2794)
							(mid -0.249642 -0.249642)
							(end -0.2794 -0.1778)
						)
						(arc
							(start -0.2794 0.1778)
							(mid -0.249642 0.249642)
							(end -0.1778 0.2794)
						)
						(arc
							(start 0.1778 0.2794)
							(mid 0.249642 0.249642)
							(end 0.2794 0.1778)
						)
						(arc
							(start 0.2794 -0.1778)
							(mid 0.249642 -0.249642)
							(end 0.1778 -0.2794)
						)
					)
					(width 0)
					(fill yes)
				)
			)
		)
		(pad "2" smd custom
			(at 0 0.4445 270)
			(size 0.1397 0.1397)
			(layers "F.Cu" "F.Mask" "F.Paste")
			(net "GND")
			(options
				(clearance outline)
				(anchor circle)
			)
			(primitives
				(gr_poly
					(pts
						(arc
							(start -0.1778 -0.2794)
							(mid -0.249642 -0.249642)
							(end -0.2794 -0.1778)
						)
						(arc
							(start -0.2794 0.1778)
							(mid -0.249642 0.249642)
							(end -0.1778 0.2794)
						)
						(arc
							(start 0.1778 0.2794)
							(mid 0.249642 0.249642)
							(end 0.2794 0.1778)
						)
						(arc
							(start 0.2794 -0.1778)
							(mid 0.249642 -0.249642)
							(end 0.1778 -0.2794)
						)
					)
					(width 0)
					(fill yes)
				)
			)
		)
	)
	(footprint ""
		(layer "F.Cu")
		(at 6.2992 -216.9668 90)
		(property "Reference" "R625"
			(at 0 0 90)
			(layer "F.SilkS")
			(hide yes)
			(effects
				(font
					(size 1.27 1.27)
				)
			)
		)
		(property "Value" "0R2J-2-GP"
			(at 0.064008 -3.993896 90)
			(unlocked yes)
			(layer "F.Fab")
			(hide yes)
			(effects
				(font
					(size 1.016 1.016)
					(thickness 0.1524)
				)
			)
		)
		(property "Device Type" "R402H16"
			(at 0.064008 -5.517896 90)
			(unlocked yes)
			(layer "F.Fab")
			(hide yes)
			(effects
				(font
					(size 1.016 1.016)
					(thickness 0.1524)
				)
			)
		)
		(duplicate_pad_numbers_are_jumpers no)
		(fp_line
			(start 0.508 -0.9398)
			(end -0.508 -0.9398)
			(stroke
				(width 0.1524)
				(type default)
			)
			(layer "F.SilkS")
		)
		(fp_line
			(start -0.508 -0.9398)
			(end -0.508 0.9398)
			(stroke
				(width 0.1524)
				(type default)
			)
			(layer "F.SilkS")
		)
		(fp_rect
			(start -0.508 0.9398)
			(end 0.508 -0.9398)
			(stroke
				(width 0)
				(type default)
			)
			(fill no)
			(layer "F.CrtYd")
		)
		(fp_rect
			(start -0.508 0.9398)
			(end 0.508 -0.9398)
			(stroke
				(width 0)
				(type default)
			)
			(fill no)
			(layer "F.Fab")
		)
		(pad "1" smd custom
			(at 0 -0.4445 90)
			(size 0.1397 0.1397)
			(layers "F.Cu" "F.Mask" "F.Paste")
			(net "P3V3_STBY_PG")
			(options
				(clearance outline)
				(anchor circle)
			)
			(primitives
				(gr_poly
					(pts
						(arc
							(start -0.1778 -0.2794)
							(mid -0.249642 -0.249642)
							(end -0.2794 -0.1778)
						)
						(arc
							(start -0.2794 0.1778)
							(mid -0.249642 0.249642)
							(end -0.1778 0.2794)
						)
						(arc
							(start 0.1778 0.2794)
							(mid 0.249642 0.249642)
							(end 0.2794 0.1778)
						)
						(arc
							(start 0.2794 -0.1778)
							(mid 0.249642 -0.249642)
							(end 0.1778 -0.2794)
						)
					)
					(width 0)
					(fill yes)
				)
			)
		)
		(pad "2" smd custom
			(at 0 0.4445 90)
			(size 0.1397 0.1397)
			(layers "F.Cu" "F.Mask" "F.Paste")
			(net "PRSNT_AND_1")
			(options
				(clearance outline)
				(anchor circle)
			)
			(primitives
				(gr_poly
					(pts
						(arc
							(start -0.1778 -0.2794)
							(mid -0.249642 -0.249642)
							(end -0.2794 -0.1778)
						)
						(arc
							(start -0.2794 0.1778)
							(mid -0.249642 0.249642)
							(end -0.1778 0.2794)
						)
						(arc
							(start 0.1778 0.2794)
							(mid 0.249642 0.249642)
							(end 0.2794 0.1778)
						)
						(arc
							(start 0.2794 -0.1778)
							(mid 0.249642 -0.249642)
							(end 0.1778 -0.2794)
						)
					)
					(width 0)
					(fill yes)
				)
			)
		)
	)
	(footprint ""
		(layer "F.Cu")
		(at 190.054992 -30.099)
		(property "Reference" "TP126"
			(at 0 0 0)
			(layer "F.SilkS")
			(hide yes)
			(effects
				(font
					(size 1.27 1.27)
				)
			)
		)
		(property "Value" "TPAD28"
			(at 0.0127 -1.8034 0)
			(unlocked yes)
			(layer "F.Fab")
			(hide yes)
			(effects
				(font
					(size 1.016 1.016)
					(thickness 0.1524)
				)
			)
		)
		(property "Device Type" "TPAD28"
			(at 0.0127 -3.3274 0)
			(unlocked yes)
			(layer "F.Fab")
			(hide yes)
			(effects
				(font
					(size 1.016 1.016)
					(thickness 0.1524)
				)
			)
		)
		(duplicate_pad_numbers_are_jumpers no)
		(fp_poly
			(pts
				(arc
					(start 0.3556 0)
					(mid -0.3556 0)
					(end 0.3556 0)
				)
			)
			(stroke
				(width 0)
				(type default)
			)
			(fill no)
			(layer "F.CrtYd")
		)
		(fp_poly
			(pts
				(arc
					(start 0.6096 0)
					(mid -0.6096 0)
					(end 0.6096 0)
				)
			)
			(stroke
				(width 0)
				(type default)
			)
			(fill no)
			(layer "F.Fab")
		)
		(pad "1" smd circle
			(at 0 0)
			(size 0.7112 0.7112)
			(layers "F.Cu" "F.Mask" "F.Paste")
			(net "NC_PHY_TXC")
		)
	)
	(footprint ""
		(layer "F.Cu")
		(at 46.62297 -134.62 -90)
		(property "Reference" "SR914"
			(at 0 0 270)
			(layer "F.SilkS")
			(hide yes)
			(effects
				(font
					(size 1.27 1.27)
				)
			)
		)
		(property "Value" "0R2J-2-GP"
			(at 0.064008 -3.993896 270)
			(unlocked yes)
			(layer "F.Fab")
			(hide yes)
			(effects
				(font
					(size 1.016 1.016)
					(thickness 0.1524)
				)
			)
		)
		(property "Device Type" "R402H16"
			(at 0.064008 -5.517896 270)
			(unlocked yes)
			(layer "F.Fab")
			(hide yes)
			(effects
				(font
					(size 1.016 1.016)
					(thickness 0.1524)
				)
			)
		)
		(duplicate_pad_numbers_are_jumpers no)
		(fp_line
			(start -0.508 -0.9398)
			(end -0.508 0.9398)
			(stroke
				(width 0.1524)
				(type default)
			)
			(layer "F.SilkS")
		)
		(fp_line
			(start 0.508 -0.9398)
			(end -0.508 -0.9398)
			(stroke
				(width 0.1524)
				(type default)
			)
			(layer "F.SilkS")
		)
		(fp_rect
			(start -0.508 0.9398)
			(end 0.508 -0.9398)
			(stroke
				(width 0)
				(type default)
			)
			(fill no)
			(layer "F.CrtYd")
		)
		(fp_rect
			(start -0.508 0.9398)
			(end 0.508 -0.9398)
			(stroke
				(width 0)
				(type default)
			)
			(fill no)
			(layer "F.Fab")
		)
		(pad "1" smd custom
			(at 0 -0.4445 270)
			(size 0.1397 0.1397)
			(layers "F.Cu" "F.Mask" "F.Paste")
			(net "BMC_EXP_RESET_N")
			(options
				(clearance outline)
				(anchor circle)
			)
			(primitives
				(gr_poly
					(pts
						(arc
							(start -0.1778 -0.2794)
							(mid -0.249642 -0.249642)
							(end -0.2794 -0.1778)
						)
						(arc
							(start -0.2794 0.1778)
							(mid -0.249642 0.249642)
							(end -0.1778 0.2794)
						)
						(arc
							(start 0.1778 0.2794)
							(mid 0.249642 0.249642)
							(end 0.2794 0.1778)
						)
						(arc
							(start 0.2794 -0.1778)
							(mid 0.249642 -0.249642)
							(end 0.1778 -0.2794)
						)
					)
					(width 0)
					(fill yes)
				)
			)
		)
		(pad "2" smd custom
			(at 0 0.4445 270)
			(size 0.1397 0.1397)
			(layers "F.Cu" "F.Mask" "F.Paste")
			(net "EXP_RST_R")
			(options
				(clearance outline)
				(anchor circle)
			)
			(primitives
				(gr_poly
					(pts
						(arc
							(start -0.1778 -0.2794)
							(mid -0.249642 -0.249642)
							(end -0.2794 -0.1778)
						)
						(arc
							(start -0.2794 0.1778)
							(mid -0.249642 0.249642)
							(end -0.1778 0.2794)
						)
						(arc
							(start 0.1778 0.2794)
							(mid 0.249642 0.249642)
							(end 0.2794 0.1778)
						)
						(arc
							(start 0.2794 -0.1778)
							(mid 0.249642 -0.249642)
							(end 0.1778 -0.2794)
						)
					)
					(width 0)
					(fill yes)
				)
			)
		)
	)
	(footprint ""
		(layer "F.Cu")
		(at 310.769 -211.201 -90)
		(property "Reference" "R575"
			(at 0 0 270)
			(layer "F.SilkS")
			(hide yes)
			(effects
				(font
					(size 1.27 1.27)
				)
			)
		)
		(property "Value" "0R2J-2-GP"
			(at 0.064008 -3.993896 270)
			(unlocked yes)
			(layer "F.Fab")
			(hide yes)
			(effects
				(font
					(size 1.016 1.016)
					(thickness 0.1524)
				)
			)
		)
		(property "Device Type" "R402H16"
			(at 0.064008 -5.517896 270)
			(unlocked yes)
			(layer "F.Fab")
			(hide yes)
			(effects
				(font
					(size 1.016 1.016)
					(thickness 0.1524)
				)
			)
		)
		(duplicate_pad_numbers_are_jumpers no)
		(fp_line
			(start -0.508 -0.9398)
			(end -0.508 0.9398)
			(stroke
				(width 0.1524)
				(type default)
			)
			(layer "F.SilkS")
		)
		(fp_line
			(start 0.508 -0.9398)
			(end -0.508 -0.9398)
			(stroke
				(width 0.1524)
				(type default)
			)
			(layer "F.SilkS")
		)
		(fp_rect
			(start -0.508 0.9398)
			(end 0.508 -0.9398)
			(stroke
				(width 0)
				(type default)
			)
			(fill no)
			(layer "F.CrtYd")
		)
		(fp_rect
			(start -0.508 0.9398)
			(end 0.508 -0.9398)
			(stroke
				(width 0)
				(type default)
			)
			(fill no)
			(layer "F.Fab")
		)
		(pad "1" smd custom
			(at 0 -0.4445 270)
			(size 0.1397 0.1397)
			(layers "F.Cu" "F.Mask" "F.Paste")
			(net "JTAG_IOC_L_TDI_R")
			(options
				(clearance outline)
				(anchor circle)
			)
			(primitives
				(gr_poly
					(pts
						(arc
							(start -0.1778 -0.2794)
							(mid -0.249642 -0.249642)
							(end -0.2794 -0.1778)
						)
						(arc
							(start -0.2794 0.1778)
							(mid -0.249642 0.249642)
							(end -0.1778 0.2794)
						)
						(arc
							(start 0.1778 0.2794)
							(mid 0.249642 0.249642)
							(end 0.2794 0.1778)
						)
						(arc
							(start 0.2794 -0.1778)
							(mid 0.249642 -0.249642)
							(end 0.1778 -0.2794)
						)
					)
					(width 0)
					(fill yes)
				)
			)
		)
		(pad "2" smd custom
			(at 0 0.4445 270)
			(size 0.1397 0.1397)
			(layers "F.Cu" "F.Mask" "F.Paste")
			(net "JTAG_IOC_L_TDI")
			(options
				(clearance outline)
				(anchor circle)
			)
			(primitives
				(gr_poly
					(pts
						(arc
							(start -0.1778 -0.2794)
							(mid -0.249642 -0.249642)
							(end -0.2794 -0.1778)
						)
						(arc
							(start -0.2794 0.1778)
							(mid -0.249642 0.249642)
							(end -0.1778 0.2794)
						)
						(arc
							(start 0.1778 0.2794)
							(mid 0.249642 0.249642)
							(end 0.2794 0.1778)
						)
						(arc
							(start 0.2794 -0.1778)
							(mid 0.249642 -0.249642)
							(end 0.1778 -0.2794)
						)
					)
					(width 0)
					(fill yes)
				)
			)
		)
	)
)
